(kicad_pcb
	(version 20260206)
	(generator "pcbnew")
	(generator_version "10.0")
	(general
		(thickness 1.6)
		(legacy_teardrops no)
	)
	(paper "A4")
	(title_block
		(title "03242023_DA0F0TMBIJ0_F0T_Motherboard_J_brd_V01_OCP.brd")
		(comment 1 "Grand Teton / footprints 767-772 of 6105")
	)
	(layers
		(0 "F.Cu" signal "TOP")
		(4 "In1.Cu" signal "GND")
		(6 "In2.Cu" signal "IN1")
		(8 "In3.Cu" signal "GND1")
		(10 "In4.Cu" signal "IN2")
		(12 "In5.Cu" signal "GND2")
		(14 "In6.Cu" signal "IN3")
		(16 "In7.Cu" signal "GND3")
		(18 "In8.Cu" signal "VCC")
		(20 "In9.Cu" signal "VCC1")
		(22 "In10.Cu" signal "GND4")
		(24 "In11.Cu" signal "IN4")
		(26 "In12.Cu" signal "GND5")
		(28 "In13.Cu" signal "IN5")
		(30 "In14.Cu" signal "GND6")
		(32 "In15.Cu" signal "IN6")
		(34 "In16.Cu" signal "GND7")
		(2 "B.Cu" signal "BOTTOM")
		(9 "F.Adhes" user "F.Adhesive")
		(11 "B.Adhes" user "B.Adhesive")
		(13 "F.Paste" user "Package Geometry/Pastemask Top")
		(15 "B.Paste" user "Package Geometry/Pastemask Bottom")
		(5 "F.SilkS" user "Ref Des/Silkscreen Top")
		(7 "B.SilkS" user "Ref Des/Silkscreen Bottom")
		(1 "F.Mask" user "Board Geometry/Soldermask Top")
		(3 "B.Mask" user "Board Geometry/Soldermask Bottom")
		(17 "Dwgs.User" user "User.Drawings")
		(19 "Cmts.User" user "User.Comments")
		(21 "Eco1.User" user "User.Eco1")
		(23 "Eco2.User" user "User.Eco2")
		(25 "Edge.Cuts" user "Board Geometry/Outline")
		(27 "Margin" user)
		(31 "F.CrtYd" user "Package Geometry/Place Bound Top")
		(29 "B.CrtYd" user "Package Geometry/Place Bound Bottom")
		(35 "F.Fab" user "Ref Des/Assembly Top")
		(33 "B.Fab" user "Ref Des/Assembly Bottom")
	)
	(footprint ""
		(layer "F.Cu")
		(at 28.532328 -98.570034)
		(property "Reference" "R3859"
			(at 0 0 0)
			(layer "F.SilkS")
			(hide yes)
			(effects
				(font
					(size 1.27 1.27)
				)
			)
		)
		(property "Value" ""
			(at 0 0 0)
			(layer "F.Fab")
			(effects
				(font
					(size 1.27 1.27)
				)
			)
		)
		(duplicate_pad_numbers_are_jumpers no)
		(fp_line
			(start -0.7874 -0.4064)
			(end 0.7874 -0.4064)
			(stroke
				(width 0.1524)
				(type default)
			)
			(layer "F.SilkS")
		)
		(fp_line
			(start -0.7874 0.4064)
			(end -0.7874 -0.4064)
			(stroke
				(width 0.1524)
				(type default)
			)
			(layer "F.SilkS")
		)
		(fp_line
			(start 0.7874 -0.4064)
			(end 0.7874 0.4064)
			(stroke
				(width 0.1524)
				(type default)
			)
			(layer "F.SilkS")
		)
		(fp_line
			(start 0.7874 0.4064)
			(end -0.7874 0.4064)
			(stroke
				(width 0.1524)
				(type default)
			)
			(layer "F.SilkS")
		)
		(fp_line
			(start -0.67945 -0.305054)
			(end -0.12065 -0.305054)
			(stroke
				(width 0.1)
				(type default)
			)
			(layer "F.Fab")
		)
		(fp_line
			(start -0.67945 0.3048)
			(end -0.67945 -0.305054)
			(stroke
				(width 0.1)
				(type default)
			)
			(layer "F.Fab")
		)
		(fp_line
			(start -0.12065 -0.305054)
			(end -0.12065 -0.2794)
			(stroke
				(width 0.1)
				(type default)
			)
			(layer "F.Fab")
		)
		(fp_line
			(start -0.12065 -0.2794)
			(end 0.12065 -0.2794)
			(stroke
				(width 0.1)
				(type default)
			)
			(layer "F.Fab")
		)
		(fp_line
			(start -0.12065 0.2794)
			(end -0.12065 0.3048)
			(stroke
				(width 0.1)
				(type default)
			)
			(layer "F.Fab")
		)
		(fp_line
			(start -0.12065 0.3048)
			(end -0.67945 0.3048)
			(stroke
				(width 0.1)
				(type default)
			)
			(layer "F.Fab")
		)
		(fp_line
			(start 0.120396 0.2794)
			(end -0.12065 0.2794)
			(stroke
				(width 0.1)
				(type default)
			)
			(layer "F.Fab")
		)
		(fp_line
			(start 0.120396 0.3048)
			(end 0.120396 0.2794)
			(stroke
				(width 0.1)
				(type default)
			)
			(layer "F.Fab")
		)
		(fp_line
			(start 0.12065 -0.3048)
			(end 0.67945 -0.3048)
			(stroke
				(width 0.1)
				(type default)
			)
			(layer "F.Fab")
		)
		(fp_line
			(start 0.12065 -0.2794)
			(end 0.12065 -0.3048)
			(stroke
				(width 0.1)
				(type default)
			)
			(layer "F.Fab")
		)
		(fp_line
			(start 0.67945 -0.3048)
			(end 0.67945 0.3048)
			(stroke
				(width 0.1)
				(type default)
			)
			(layer "F.Fab")
		)
		(fp_line
			(start 0.67945 0.3048)
			(end 0.120396 0.3048)
			(stroke
				(width 0.1)
				(type default)
			)
			(layer "F.Fab")
		)
		(pad "1" smd rect
			(at -0.40005 0 180)
			(size 0.4572 0.508)
			(layers "F.Cu" "F.Mask" "F.Paste")
			(net "P12V_OCP_V3_2_ISENSE_MAM_MAM")
		)
		(pad "2" smd rect
			(at 0.40005 0 180)
			(size 0.4572 0.508)
			(layers "F.Cu" "F.Mask" "F.Paste")
			(net "P12V_OCP_V3_2_ISENSE_MAM")
		)
	)
	(footprint ""
		(layer "F.Cu")
		(at 274.495006 -21.259292 180)
		(property "Reference" "R3185"
			(at 0 0 180)
			(layer "F.SilkS")
			(hide yes)
			(effects
				(font
					(size 1.27 1.27)
				)
			)
		)
		(property "Value" ""
			(at 0 0 180)
			(layer "F.Fab")
			(effects
				(font
					(size 1.27 1.27)
				)
			)
		)
		(duplicate_pad_numbers_are_jumpers no)
		(fp_line
			(start 0.7874 0.4064)
			(end -0.7874 0.4064)
			(stroke
				(width 0.1524)
				(type default)
			)
			(layer "F.SilkS")
		)
		(fp_line
			(start 0.7874 -0.4064)
			(end 0.7874 0.4064)
			(stroke
				(width 0.1524)
				(type default)
			)
			(layer "F.SilkS")
		)
		(fp_line
			(start -0.7874 0.4064)
			(end -0.7874 -0.4064)
			(stroke
				(width 0.1524)
				(type default)
			)
			(layer "F.SilkS")
		)
		(fp_line
			(start -0.7874 -0.4064)
			(end 0.7874 -0.4064)
			(stroke
				(width 0.1524)
				(type default)
			)
			(layer "F.SilkS")
		)
		(fp_line
			(start 0.67945 0.3048)
			(end 0.120396 0.3048)
			(stroke
				(width 0.1)
				(type default)
			)
			(layer "F.Fab")
		)
		(fp_line
			(start 0.67945 -0.3048)
			(end 0.67945 0.3048)
			(stroke
				(width 0.1)
				(type default)
			)
			(layer "F.Fab")
		)
		(fp_line
			(start 0.12065 -0.2794)
			(end 0.12065 -0.3048)
			(stroke
				(width 0.1)
				(type default)
			)
			(layer "F.Fab")
		)
		(fp_line
			(start 0.12065 -0.3048)
			(end 0.67945 -0.3048)
			(stroke
				(width 0.1)
				(type default)
			)
			(layer "F.Fab")
		)
		(fp_line
			(start 0.120396 0.3048)
			(end 0.120396 0.2794)
			(stroke
				(width 0.1)
				(type default)
			)
			(layer "F.Fab")
		)
		(fp_line
			(start 0.120396 0.2794)
			(end -0.12065 0.2794)
			(stroke
				(width 0.1)
				(type default)
			)
			(layer "F.Fab")
		)
		(fp_line
			(start -0.12065 0.3048)
			(end -0.67945 0.3048)
			(stroke
				(width 0.1)
				(type default)
			)
			(layer "F.Fab")
		)
		(fp_line
			(start -0.12065 0.2794)
			(end -0.12065 0.3048)
			(stroke
				(width 0.1)
				(type default)
			)
			(layer "F.Fab")
		)
		(fp_line
			(start -0.12065 -0.2794)
			(end 0.12065 -0.2794)
			(stroke
				(width 0.1)
				(type default)
			)
			(layer "F.Fab")
		)
		(fp_line
			(start -0.12065 -0.305054)
			(end -0.12065 -0.2794)
			(stroke
				(width 0.1)
				(type default)
			)
			(layer "F.Fab")
		)
		(fp_line
			(start -0.67945 0.3048)
			(end -0.67945 -0.305054)
			(stroke
				(width 0.1)
				(type default)
			)
			(layer "F.Fab")
		)
		(fp_line
			(start -0.67945 -0.305054)
			(end -0.12065 -0.305054)
			(stroke
				(width 0.1)
				(type default)
			)
			(layer "F.Fab")
		)
		(pad "1" smd circle
			(at -0.40005 0 180)
			(size 0 0)
			(layers "F.Cu" "F.Mask" "F.Paste")
			(net "OCP_V3_2_WAKE_BUFF_N")
		)
		(pad "2" smd circle
			(at 0.40005 0 180)
			(size 0 0)
			(layers "F.Cu" "F.Mask" "F.Paste")
			(net "OCP_V3_2_WAKE_BUFF_R_N")
		)
	)
	(footprint ""
		(layer "F.Cu")
		(at 432.80584 -138.557762 -90)
		(property "Reference" "R2386"
			(at 0 0 270)
			(layer "F.SilkS")
			(hide yes)
			(effects
				(font
					(size 1.27 1.27)
				)
			)
		)
		(property "Value" ""
			(at 0 0 270)
			(layer "F.Fab")
			(effects
				(font
					(size 1.27 1.27)
				)
			)
		)
		(duplicate_pad_numbers_are_jumpers no)
		(fp_line
			(start -0.7874 0.4064)
			(end -0.7874 -0.4064)
			(stroke
				(width 0.1524)
				(type default)
			)
			(layer "F.SilkS")
		)
		(fp_line
			(start 0.7874 0.4064)
			(end -0.7874 0.4064)
			(stroke
				(width 0.1524)
				(type default)
			)
			(layer "F.SilkS")
		)
		(fp_line
			(start -0.7874 -0.4064)
			(end 0.7874 -0.4064)
			(stroke
				(width 0.1524)
				(type default)
			)
			(layer "F.SilkS")
		)
		(fp_line
			(start 0.7874 -0.4064)
			(end 0.7874 0.4064)
			(stroke
				(width 0.1524)
				(type default)
			)
			(layer "F.SilkS")
		)
		(fp_line
			(start -0.67945 0.3048)
			(end -0.67945 -0.305054)
			(stroke
				(width 0.1)
				(type default)
			)
			(layer "F.Fab")
		)
		(fp_line
			(start -0.12065 0.3048)
			(end -0.67945 0.3048)
			(stroke
				(width 0.1)
				(type default)
			)
			(layer "F.Fab")
		)
		(fp_line
			(start 0.120396 0.3048)
			(end 0.120396 0.2794)
			(stroke
				(width 0.1)
				(type default)
			)
			(layer "F.Fab")
		)
		(fp_line
			(start 0.67945 0.3048)
			(end 0.120396 0.3048)
			(stroke
				(width 0.1)
				(type default)
			)
			(layer "F.Fab")
		)
		(fp_line
			(start -0.12065 0.2794)
			(end -0.12065 0.3048)
			(stroke
				(width 0.1)
				(type default)
			)
			(layer "F.Fab")
		)
		(fp_line
			(start 0.120396 0.2794)
			(end -0.12065 0.2794)
			(stroke
				(width 0.1)
				(type default)
			)
			(layer "F.Fab")
		)
		(fp_line
			(start -0.12065 -0.2794)
			(end 0.12065 -0.2794)
			(stroke
				(width 0.1)
				(type default)
			)
			(layer "F.Fab")
		)
		(fp_line
			(start 0.12065 -0.2794)
			(end 0.12065 -0.3048)
			(stroke
				(width 0.1)
				(type default)
			)
			(layer "F.Fab")
		)
		(fp_line
			(start 0.12065 -0.3048)
			(end 0.67945 -0.3048)
			(stroke
				(width 0.1)
				(type default)
			)
			(layer "F.Fab")
		)
		(fp_line
			(start 0.67945 -0.3048)
			(end 0.67945 0.3048)
			(stroke
				(width 0.1)
				(type default)
			)
			(layer "F.Fab")
		)
		(fp_line
			(start -0.67945 -0.305054)
			(end -0.12065 -0.305054)
			(stroke
				(width 0.1)
				(type default)
			)
			(layer "F.Fab")
		)
		(fp_line
			(start -0.12065 -0.305054)
			(end -0.12065 -0.2794)
			(stroke
				(width 0.1)
				(type default)
			)
			(layer "F.Fab")
		)
		(pad "1" smd circle
			(at -0.40005 0 270)
			(size 0 0)
			(layers "F.Cu" "F.Mask" "F.Paste")
			(net "PVNN_TERM_CPU0")
		)
		(pad "2" smd circle
			(at 0.40005 0 270)
			(size 0 0)
			(layers "F.Cu" "F.Mask" "F.Paste")
			(net "SVID_DIO0_CPU0_R")
		)
	)
	(footprint ""
		(layer "F.Cu")
		(at 292.61054 -94.800674)
		(property "Reference" "R710"
			(at 0 0 0)
			(layer "F.SilkS")
			(hide yes)
			(effects
				(font
					(size 1.27 1.27)
				)
			)
		)
		(property "Value" ""
			(at 0 0 0)
			(layer "F.Fab")
			(effects
				(font
					(size 1.27 1.27)
				)
			)
		)
		(duplicate_pad_numbers_are_jumpers no)
		(fp_line
			(start -0.7874 -0.4064)
			(end 0.7874 -0.4064)
			(stroke
				(width 0.1524)
				(type default)
			)
			(layer "F.SilkS")
		)
		(fp_line
			(start -0.7874 0.4064)
			(end -0.7874 -0.4064)
			(stroke
				(width 0.1524)
				(type default)
			)
			(layer "F.SilkS")
		)
		(fp_line
			(start 0.7874 -0.4064)
			(end 0.7874 0.4064)
			(stroke
				(width 0.1524)
				(type default)
			)
			(layer "F.SilkS")
		)
		(fp_line
			(start 0.7874 0.4064)
			(end -0.7874 0.4064)
			(stroke
				(width 0.1524)
				(type default)
			)
			(layer "F.SilkS")
		)
		(fp_line
			(start -0.67945 -0.305054)
			(end -0.12065 -0.305054)
			(stroke
				(width 0.1)
				(type default)
			)
			(layer "F.Fab")
		)
		(fp_line
			(start -0.67945 0.3048)
			(end -0.67945 -0.305054)
			(stroke
				(width 0.1)
				(type default)
			)
			(layer "F.Fab")
		)
		(fp_line
			(start -0.12065 -0.305054)
			(end -0.12065 -0.2794)
			(stroke
				(width 0.1)
				(type default)
			)
			(layer "F.Fab")
		)
		(fp_line
			(start -0.12065 -0.2794)
			(end 0.12065 -0.2794)
			(stroke
				(width 0.1)
				(type default)
			)
			(layer "F.Fab")
		)
		(fp_line
			(start -0.12065 0.2794)
			(end -0.12065 0.3048)
			(stroke
				(width 0.1)
				(type default)
			)
			(layer "F.Fab")
		)
		(fp_line
			(start -0.12065 0.3048)
			(end -0.67945 0.3048)
			(stroke
				(width 0.1)
				(type default)
			)
			(layer "F.Fab")
		)
		(fp_line
			(start 0.120396 0.2794)
			(end -0.12065 0.2794)
			(stroke
				(width 0.1)
				(type default)
			)
			(layer "F.Fab")
		)
		(fp_line
			(start 0.120396 0.3048)
			(end 0.120396 0.2794)
			(stroke
				(width 0.1)
				(type default)
			)
			(layer "F.Fab")
		)
		(fp_line
			(start 0.12065 -0.3048)
			(end 0.67945 -0.3048)
			(stroke
				(width 0.1)
				(type default)
			)
			(layer "F.Fab")
		)
		(fp_line
			(start 0.12065 -0.2794)
			(end 0.12065 -0.3048)
			(stroke
				(width 0.1)
				(type default)
			)
			(layer "F.Fab")
		)
		(fp_line
			(start 0.67945 -0.3048)
			(end 0.67945 0.3048)
			(stroke
				(width 0.1)
				(type default)
			)
			(layer "F.Fab")
		)
		(fp_line
			(start 0.67945 0.3048)
			(end 0.120396 0.3048)
			(stroke
				(width 0.1)
				(type default)
			)
			(layer "F.Fab")
		)
		(pad "1" smd circle
			(at -0.40005 0)
			(size 0 0)
			(layers "F.Cu" "F.Mask" "F.Paste")
			(net "PD_MB_FRU_WP")
		)
		(pad "2" smd circle
			(at 0.40005 0)
			(size 0 0)
			(layers "F.Cu" "F.Mask" "F.Paste")
			(net "GND")
		)
	)
	(footprint ""
		(layer "F.Cu")
		(at 286.033718 -367.357152 -90)
		(property "Reference" "PC1352"
			(at 0 0 270)
			(layer "F.SilkS")
			(hide yes)
			(effects
				(font
					(size 1.27 1.27)
				)
			)
		)
		(property "Value" ""
			(at 0 0 270)
			(layer "F.Fab")
			(effects
				(font
					(size 1.27 1.27)
				)
			)
		)
		(duplicate_pad_numbers_are_jumpers no)
		(fp_line
			(start -0.7874 0.4064)
			(end -0.7874 -0.4064)
			(stroke
				(width 0.1524)
				(type default)
			)
			(layer "F.SilkS")
		)
		(fp_line
			(start 0.7874 0.4064)
			(end -0.7874 0.4064)
			(stroke
				(width 0.1524)
				(type default)
			)
			(layer "F.SilkS")
		)
		(fp_line
			(start -0.7874 -0.4064)
			(end 0.7874 -0.4064)
			(stroke
				(width 0.1524)
				(type default)
			)
			(layer "F.SilkS")
		)
		(fp_line
			(start 0.7874 -0.4064)
			(end 0.7874 0.4064)
			(stroke
				(width 0.1524)
				(type default)
			)
			(layer "F.SilkS")
		)
		(fp_line
			(start -0.67945 0.3048)
			(end -0.67945 -0.305054)
			(stroke
				(width 0.1)
				(type default)
			)
			(layer "F.Fab")
		)
		(fp_line
			(start -0.12065 0.3048)
			(end -0.67945 0.3048)
			(stroke
				(width 0.1)
				(type default)
			)
			(layer "F.Fab")
		)
		(fp_line
			(start 0.120396 0.3048)
			(end 0.120396 0.2794)
			(stroke
				(width 0.1)
				(type default)
			)
			(layer "F.Fab")
		)
		(fp_line
			(start 0.67945 0.3048)
			(end 0.120396 0.3048)
			(stroke
				(width 0.1)
				(type default)
			)
			(layer "F.Fab")
		)
		(fp_line
			(start -0.12065 0.2794)
			(end -0.12065 0.3048)
			(stroke
				(width 0.1)
				(type default)
			)
			(layer "F.Fab")
		)
		(fp_line
			(start 0.120396 0.2794)
			(end -0.12065 0.2794)
			(stroke
				(width 0.1)
				(type default)
			)
			(layer "F.Fab")
		)
		(fp_line
			(start -0.12065 -0.2794)
			(end 0.12065 -0.2794)
			(stroke
				(width 0.1)
				(type default)
			)
			(layer "F.Fab")
		)
		(fp_line
			(start 0.12065 -0.2794)
			(end 0.12065 -0.3048)
			(stroke
				(width 0.1)
				(type default)
			)
			(layer "F.Fab")
		)
		(fp_line
			(start 0.12065 -0.3048)
			(end 0.67945 -0.3048)
			(stroke
				(width 0.1)
				(type default)
			)
			(layer "F.Fab")
		)
		(fp_line
			(start 0.67945 -0.3048)
			(end 0.67945 0.3048)
			(stroke
				(width 0.1)
				(type default)
			)
			(layer "F.Fab")
		)
		(fp_line
			(start -0.67945 -0.305054)
			(end -0.12065 -0.305054)
			(stroke
				(width 0.1)
				(type default)
			)
			(layer "F.Fab")
		)
		(fp_line
			(start -0.12065 -0.305054)
			(end -0.12065 -0.2794)
			(stroke
				(width 0.1)
				(type default)
			)
			(layer "F.Fab")
		)
		(pad "1" smd circle
			(at -0.40005 0 270)
			(size 0 0)
			(layers "F.Cu" "F.Mask" "F.Paste")
			(net "GND")
		)
		(pad "2" smd circle
			(at 0.40005 0 270)
			(size 0 0)
			(layers "F.Cu" "F.Mask" "F.Paste")
			(net "PVCCIN_CPU0_VREF")
		)
	)
	(footprint ""
		(layer "F.Cu")
		(at 128.401572 -132.034026)
		(property "Reference" "R2565"
			(at 0 0 0)
			(layer "F.SilkS")
			(hide yes)
			(effects
				(font
					(size 1.27 1.27)
				)
			)
		)
		(property "Value" ""
			(at 0 0 0)
			(layer "F.Fab")
			(effects
				(font
					(size 1.27 1.27)
				)
			)
		)
		(duplicate_pad_numbers_are_jumpers no)
		(fp_line
			(start -0.7874 -0.4064)
			(end 0.7874 -0.4064)
			(stroke
				(width 0.1524)
				(type default)
			)
			(layer "F.SilkS")
		)
		(fp_line
			(start -0.7874 0.4064)
			(end -0.7874 -0.4064)
			(stroke
				(width 0.1524)
				(type default)
			)
			(layer "F.SilkS")
		)
		(fp_line
			(start 0.7874 -0.4064)
			(end 0.7874 0.4064)
			(stroke
				(width 0.1524)
				(type default)
			)
			(layer "F.SilkS")
		)
		(fp_line
			(start 0.7874 0.4064)
			(end -0.7874 0.4064)
			(stroke
				(width 0.1524)
				(type default)
			)
			(layer "F.SilkS")
		)
		(fp_line
			(start -0.67945 -0.305054)
			(end -0.12065 -0.305054)
			(stroke
				(width 0.1)
				(type default)
			)
			(layer "F.Fab")
		)
		(fp_line
			(start -0.67945 0.3048)
			(end -0.67945 -0.305054)
			(stroke
				(width 0.1)
				(type default)
			)
			(layer "F.Fab")
		)
		(fp_line
			(start -0.12065 -0.305054)
			(end -0.12065 -0.2794)
			(stroke
				(width 0.1)
				(type default)
			)
			(layer "F.Fab")
		)
		(fp_line
			(start -0.12065 -0.2794)
			(end 0.12065 -0.2794)
			(stroke
				(width 0.1)
				(type default)
			)
			(layer "F.Fab")
		)
		(fp_line
			(start -0.12065 0.2794)
			(end -0.12065 0.3048)
			(stroke
				(width 0.1)
				(type default)
			)
			(layer "F.Fab")
		)
		(fp_line
			(start -0.12065 0.3048)
			(end -0.67945 0.3048)
			(stroke
				(width 0.1)
				(type default)
			)
			(layer "F.Fab")
		)
		(fp_line
			(start 0.120396 0.2794)
			(end -0.12065 0.2794)
			(stroke
				(width 0.1)
				(type default)
			)
			(layer "F.Fab")
		)
		(fp_line
			(start 0.120396 0.3048)
			(end 0.120396 0.2794)
			(stroke
				(width 0.1)
				(type default)
			)
			(layer "F.Fab")
		)
		(fp_line
			(start 0.12065 -0.3048)
			(end 0.67945 -0.3048)
			(stroke
				(width 0.1)
				(type default)
			)
			(layer "F.Fab")
		)
		(fp_line
			(start 0.12065 -0.2794)
			(end 0.12065 -0.3048)
			(stroke
				(width 0.1)
				(type default)
			)
			(layer "F.Fab")
		)
		(fp_line
			(start 0.67945 -0.3048)
			(end 0.67945 0.3048)
			(stroke
				(width 0.1)
				(type default)
			)
			(layer "F.Fab")
		)
		(fp_line
			(start 0.67945 0.3048)
			(end 0.120396 0.3048)
			(stroke
				(width 0.1)
				(type default)
			)
			(layer "F.Fab")
		)
		(pad "1" smd circle
			(at -0.40005 0)
			(size 0 0)
			(layers "F.Cu" "F.Mask" "F.Paste")
			(net "SMB_FRU_3V3AUX_SCL_R")
		)
		(pad "2" smd circle
			(at 0.40005 0)
			(size 0 0)
			(layers "F.Cu" "F.Mask" "F.Paste")
			(net "SMB_FRU_3V3AUX_SCL")
		)
	)
)
